(kicad_pcb
	(version 20260206)
	(generator "pcbnew")
	(generator_version "10.0")
	(general
		(thickness 1.6)
		(legacy_teardrops no)
	)
	(paper "A4")
	(title_block
		(title "Wiwynn_Tioga_Pass_MB.brd")
		(comment 1 "Tioga Pass / footprints 3100-3106 of 4770")
	)
	(layers
		(0 "F.Cu" signal "TOP")
		(4 "In1.Cu" signal "L2GND")
		(6 "In2.Cu" signal "L3")
		(8 "In3.Cu" signal "L4GND")
		(10 "In4.Cu" signal "L5")
		(12 "In5.Cu" signal "L6GND")
		(14 "In6.Cu" signal "L7VCC")
		(16 "In7.Cu" signal "L8VCC")
		(18 "In8.Cu" signal "L9GND")
		(20 "In9.Cu" signal "L10")
		(22 "In10.Cu" signal "L11GND")
		(24 "In11.Cu" signal "L12")
		(26 "In12.Cu" signal "L13GND")
		(2 "B.Cu" signal "BOTTOM")
		(9 "F.Adhes" user "F.Adhesive")
		(11 "B.Adhes" user "B.Adhesive")
		(13 "F.Paste" user "Package Geometry/Pastemask Top")
		(15 "B.Paste" user "Package Geometry/Pastemask Bottom")
		(5 "F.SilkS" user "Ref Des/Silkscreen Top")
		(7 "B.SilkS" user "Ref Des/Silkscreen Bottom")
		(1 "F.Mask" user "Board Geometry/Soldermask Top")
		(3 "B.Mask" user "Board Geometry/Soldermask Bottom")
		(17 "Dwgs.User" user "User.Drawings")
		(19 "Cmts.User" user "User.Comments")
		(21 "Eco1.User" user "User.Eco1")
		(23 "Eco2.User" user "User.Eco2")
		(25 "Edge.Cuts" user "Board Geometry/Outline")
		(27 "Margin" user)
		(31 "F.CrtYd" user "Package Geometry/Place Bound Top")
		(29 "B.CrtYd" user "Package Geometry/Place Bound Bottom")
		(35 "F.Fab" user "Ref Des/Assembly Top")
		(33 "B.Fab" user "Ref Des/Assembly Bottom")
	)
	(footprint ""
		(layer "B.Cu")
		(at 21.717 -69.85 180)
		(property "Reference" "R9P28"
			(at 0 0 0)
			(layer "B.SilkS")
			(hide yes)
			(effects
				(font
					(size 1.27 1.27)
				)
				(justify mirror)
			)
		)
		(property "Value" ""
			(at 0 0 0)
			(layer "B.Fab")
			(effects
				(font
					(size 1.27 1.27)
				)
				(justify mirror)
			)
		)
		(duplicate_pad_numbers_are_jumpers no)
		(fp_poly
			(pts
				(xy 0.2794 -0.1016) (xy -0.2794 -0.1016) (xy -0.2794 0.9906) (xy 0.2794 0.9906)
			)
			(stroke
				(width 0)
				(type default)
			)
			(fill no)
			(layer "B.CrtYd")
		)
		(fp_line
			(start 0.2794 0.9906)
			(end -0.2794 0.9906)
			(stroke
				(width 0.1)
				(type default)
			)
			(layer "B.Fab")
		)
		(fp_line
			(start 0.2794 -0.1016)
			(end 0.2794 0.9906)
			(stroke
				(width 0.1)
				(type default)
			)
			(layer "B.Fab")
		)
		(fp_line
			(start -0.2794 0.9906)
			(end -0.2794 -0.1016)
			(stroke
				(width 0.1)
				(type default)
			)
			(layer "B.Fab")
		)
		(fp_line
			(start -0.2794 -0.1016)
			(end 0.2794 -0.1016)
			(stroke
				(width 0.1)
				(type default)
			)
			(layer "B.Fab")
		)
		(pad "1" smd rect
			(at 0 0)
			(size 0.508 0.508)
			(layers "B.Cu" "B.Mask" "B.Paste")
			(net "P12V_PSU")
		)
		(pad "2" smd rect
			(at 0 0.889)
			(size 0.508 0.508)
			(layers "B.Cu" "B.Mask" "B.Paste")
			(net "A_HSC_OV")
		)
		(zone
			(layer "B.Cu")
			(hatch none 0.5)
			(connect_pads
				(clearance 0)
			)
			(min_thickness 0.25)
			(keepout
				(tracks not_allowed)
				(vias allowed)
				(pads allowed)
				(copperpour not_allowed)
				(footprints allowed)
			)
			(placement
				(enabled no)
				(sheetname "")
			)
			(fill
				(thermal_gap 0.5)
				(thermal_bridge_width 0.5)
				(island_removal_mode 0)
			)
			(polygon
				(pts
					(xy 21.463 -70.485) (xy 21.971 -70.485) (xy 21.971 -70.104) (xy 21.463 -70.104)
				)
			)
		)
		(zone
			(layer "B.Cu")
			(hatch none 0.5)
			(connect_pads
				(clearance 0)
			)
			(min_thickness 0.25)
			(keepout
				(tracks allowed)
				(vias not_allowed)
				(pads allowed)
				(copperpour not_allowed)
				(footprints allowed)
			)
			(placement
				(enabled no)
				(sheetname "")
			)
			(fill
				(thermal_gap 0.5)
				(thermal_bridge_width 0.5)
				(island_removal_mode 0)
			)
			(polygon
				(pts
					(xy 21.463 -70.104) (xy 21.971 -70.104) (xy 21.971 -70.485) (xy 21.463 -70.485)
				)
			)
		)
	)
	(footprint ""
		(layer "B.Cu")
		(at 349.123 -83.5406)
		(property "Reference" "C3P5"
			(at 0 0 0)
			(layer "B.SilkS")
			(hide yes)
			(effects
				(font
					(size 1.27 1.27)
				)
				(justify mirror)
			)
		)
		(property "Value" ""
			(at 0 0 0)
			(layer "B.Fab")
			(effects
				(font
					(size 1.27 1.27)
				)
				(justify mirror)
			)
		)
		(duplicate_pad_numbers_are_jumpers no)
		(fp_poly
			(pts
				(xy -0.3048 -0.1016) (xy -0.3048 0.9906) (xy 0.3048 0.9906) (xy 0.3048 -0.1016)
			)
			(stroke
				(width 0)
				(type default)
			)
			(fill no)
			(layer "B.CrtYd")
		)
		(fp_line
			(start -0.3048 -0.1016)
			(end 0.3048 -0.1016)
			(stroke
				(width 0.1)
				(type default)
			)
			(layer "B.Fab")
		)
		(fp_line
			(start -0.3048 0.9906)
			(end -0.3048 -0.1016)
			(stroke
				(width 0.1)
				(type default)
			)
			(layer "B.Fab")
		)
		(fp_line
			(start 0.3048 -0.1016)
			(end 0.3048 0.9906)
			(stroke
				(width 0.1)
				(type default)
			)
			(layer "B.Fab")
		)
		(fp_line
			(start 0.3048 0.9906)
			(end -0.3048 0.9906)
			(stroke
				(width 0.1)
				(type default)
			)
			(layer "B.Fab")
		)
		(pad "1" smd rect
			(at 0 0 180)
			(size 0.508 0.508)
			(layers "B.Cu" "B.Mask" "B.Paste")
			(net "VR_PVCCIO_CPU0_VD12")
		)
		(pad "2" smd rect
			(at 0 0.889 180)
			(size 0.508 0.508)
			(layers "B.Cu" "B.Mask" "B.Paste")
			(net "GND")
		)
		(zone
			(layer "B.Cu")
			(hatch none 0.5)
			(connect_pads
				(clearance 0)
			)
			(min_thickness 0.25)
			(keepout
				(tracks allowed)
				(vias not_allowed)
				(pads allowed)
				(copperpour not_allowed)
				(footprints allowed)
			)
			(placement
				(enabled no)
				(sheetname "")
			)
			(fill
				(thermal_gap 0.5)
				(thermal_bridge_width 0.5)
				(island_removal_mode 0)
			)
			(polygon
				(pts
					(xy 349.377 -83.2866) (xy 348.869 -83.2866) (xy 348.869 -82.9056) (xy 349.377 -82.9056)
				)
			)
		)
		(zone
			(layer "B.Cu")
			(hatch none 0.5)
			(connect_pads
				(clearance 0)
			)
			(min_thickness 0.25)
			(keepout
				(tracks not_allowed)
				(vias allowed)
				(pads allowed)
				(copperpour not_allowed)
				(footprints allowed)
			)
			(placement
				(enabled no)
				(sheetname "")
			)
			(fill
				(thermal_gap 0.5)
				(thermal_bridge_width 0.5)
				(island_removal_mode 0)
			)
			(polygon
				(pts
					(xy 349.377 -82.9056) (xy 348.869 -82.9056) (xy 348.869 -83.2866) (xy 349.377 -83.2866)
				)
			)
		)
	)
	(footprint ""
		(layer "B.Cu")
		(at 425.8056 -16.764 180)
		(property "Reference" "R1U54"
			(at 0 0 0)
			(layer "B.SilkS")
			(hide yes)
			(effects
				(font
					(size 1.27 1.27)
				)
				(justify mirror)
			)
		)
		(property "Value" ""
			(at 0 0 0)
			(layer "B.Fab")
			(effects
				(font
					(size 1.27 1.27)
				)
				(justify mirror)
			)
		)
		(duplicate_pad_numbers_are_jumpers no)
		(fp_poly
			(pts
				(xy 0.2794 -0.1016) (xy -0.2794 -0.1016) (xy -0.2794 0.9906) (xy 0.2794 0.9906)
			)
			(stroke
				(width 0)
				(type default)
			)
			(fill no)
			(layer "B.CrtYd")
		)
		(fp_line
			(start 0.2794 0.9906)
			(end -0.2794 0.9906)
			(stroke
				(width 0.1)
				(type default)
			)
			(layer "B.Fab")
		)
		(fp_line
			(start 0.2794 -0.1016)
			(end 0.2794 0.9906)
			(stroke
				(width 0.1)
				(type default)
			)
			(layer "B.Fab")
		)
		(fp_line
			(start -0.2794 0.9906)
			(end -0.2794 -0.1016)
			(stroke
				(width 0.1)
				(type default)
			)
			(layer "B.Fab")
		)
		(fp_line
			(start -0.2794 -0.1016)
			(end 0.2794 -0.1016)
			(stroke
				(width 0.1)
				(type default)
			)
			(layer "B.Fab")
		)
		(pad "1" smd rect
			(at 0 0)
			(size 0.508 0.508)
			(layers "B.Cu" "B.Mask" "B.Paste")
			(net "H_CPU1_MEMGHJ_MEMHOT_LVT3_N")
		)
		(pad "2" smd rect
			(at 0 0.889)
			(size 0.508 0.508)
			(layers "B.Cu" "B.Mask" "B.Paste")
			(net "H_CPU1_MEMGHJ_MEMHOT_LVT3_BMC_N")
		)
		(zone
			(layer "B.Cu")
			(hatch none 0.5)
			(connect_pads
				(clearance 0)
			)
			(min_thickness 0.25)
			(keepout
				(tracks not_allowed)
				(vias allowed)
				(pads allowed)
				(copperpour not_allowed)
				(footprints allowed)
			)
			(placement
				(enabled no)
				(sheetname "")
			)
			(fill
				(thermal_gap 0.5)
				(thermal_bridge_width 0.5)
				(island_removal_mode 0)
			)
			(polygon
				(pts
					(xy 425.5516 -17.399) (xy 426.0596 -17.399) (xy 426.0596 -17.018) (xy 425.5516 -17.018)
				)
			)
		)
		(zone
			(layer "B.Cu")
			(hatch none 0.5)
			(connect_pads
				(clearance 0)
			)
			(min_thickness 0.25)
			(keepout
				(tracks allowed)
				(vias not_allowed)
				(pads allowed)
				(copperpour not_allowed)
				(footprints allowed)
			)
			(placement
				(enabled no)
				(sheetname "")
			)
			(fill
				(thermal_gap 0.5)
				(thermal_bridge_width 0.5)
				(island_removal_mode 0)
			)
			(polygon
				(pts
					(xy 425.5516 -17.018) (xy 426.0596 -17.018) (xy 426.0596 -17.399) (xy 425.5516 -17.399)
				)
			)
		)
	)
	(footprint ""
		(layer "B.Cu")
		(at 349.631 -133.223 180)
		(property "Reference" "C3M8"
			(at 0 0 0)
			(layer "B.SilkS")
			(hide yes)
			(effects
				(font
					(size 1.27 1.27)
				)
				(justify mirror)
			)
		)
		(property "Value" ""
			(at 0 0 0)
			(layer "B.Fab")
			(effects
				(font
					(size 1.27 1.27)
				)
				(justify mirror)
			)
		)
		(duplicate_pad_numbers_are_jumpers no)
		(fp_poly
			(pts
				(xy 0.7239 -0.2159) (xy -0.7239 -0.2159) (xy -0.7239 1.9939) (xy 0.7239 1.9939)
			)
			(stroke
				(width 0)
				(type default)
			)
			(fill no)
			(layer "B.CrtYd")
		)
		(fp_line
			(start 0.7239 1.9939)
			(end -0.7239 1.9939)
			(stroke
				(width 0.1)
				(type default)
			)
			(layer "B.Fab")
		)
		(fp_line
			(start 0.7239 -0.2159)
			(end 0.7239 1.9939)
			(stroke
				(width 0.1)
				(type default)
			)
			(layer "B.Fab")
		)
		(fp_line
			(start -0.7239 1.9939)
			(end -0.7239 -0.2159)
			(stroke
				(width 0.1)
				(type default)
			)
			(layer "B.Fab")
		)
		(fp_line
			(start -0.7239 -0.2159)
			(end 0.7239 -0.2159)
			(stroke
				(width 0.1)
				(type default)
			)
			(layer "B.Fab")
		)
		(pad "1" smd rect
			(at 0 0)
			(size 1.27 1.016)
			(layers "B.Cu" "B.Mask" "B.Paste")
			(net "VR_FET_SW_P12V_STBY_PVPP_DEF")
		)
		(pad "2" smd rect
			(at 0 1.778)
			(size 1.27 1.016)
			(layers "B.Cu" "B.Mask" "B.Paste")
			(net "GND")
		)
		(zone
			(layer "B.Cu")
			(hatch none 0.5)
			(connect_pads
				(clearance 0)
			)
			(min_thickness 0.25)
			(keepout
				(tracks not_allowed)
				(vias allowed)
				(pads allowed)
				(copperpour not_allowed)
				(footprints allowed)
			)
			(placement
				(enabled no)
				(sheetname "")
			)
			(fill
				(thermal_gap 0.5)
				(thermal_bridge_width 0.5)
				(island_removal_mode 0)
			)
			(polygon
				(pts
					(xy 348.996 -133.731) (xy 350.266 -133.731) (xy 350.266 -134.493) (xy 348.996 -134.493)
				)
			)
		)
	)
	(footprint ""
		(layer "B.Cu")
		(at 387.457188 -57.81675 90)
		(property "Reference" "R8F7"
			(at 0 0 90)
			(layer "B.SilkS")
			(hide yes)
			(effects
				(font
					(size 1.27 1.27)
				)
				(justify mirror)
			)
		)
		(property "Value" ""
			(at 0 0 90)
			(layer "B.Fab")
			(effects
				(font
					(size 1.27 1.27)
				)
				(justify mirror)
			)
		)
		(duplicate_pad_numbers_are_jumpers no)
		(fp_poly
			(pts
				(xy 0.2794 -0.1016) (xy -0.2794 -0.1016) (xy -0.2794 0.9906) (xy 0.2794 0.9906)
			)
			(stroke
				(width 0)
				(type default)
			)
			(fill no)
			(layer "B.CrtYd")
		)
		(fp_line
			(start 0.2794 -0.1016)
			(end 0.2794 0.9906)
			(stroke
				(width 0.1)
				(type default)
			)
			(layer "B.Fab")
		)
		(fp_line
			(start -0.2794 -0.1016)
			(end 0.2794 -0.1016)
			(stroke
				(width 0.1)
				(type default)
			)
			(layer "B.Fab")
		)
		(fp_line
			(start 0.2794 0.9906)
			(end -0.2794 0.9906)
			(stroke
				(width 0.1)
				(type default)
			)
			(layer "B.Fab")
		)
		(fp_line
			(start -0.2794 0.9906)
			(end -0.2794 -0.1016)
			(stroke
				(width 0.1)
				(type default)
			)
			(layer "B.Fab")
		)
		(pad "1" smd rect
			(at 0 0 270)
			(size 0.508 0.508)
			(layers "B.Cu" "B.Mask" "B.Paste")
			(net "SPI_SWITCH_CLK")
		)
		(pad "2" smd rect
			(at 0 0.889 270)
			(size 0.508 0.508)
			(layers "B.Cu" "B.Mask" "B.Paste")
			(net "SPI_CLK_R1")
		)
		(zone
			(layer "B.Cu")
			(hatch none 0.5)
			(connect_pads
				(clearance 0)
			)
			(min_thickness 0.25)
			(keepout
				(tracks allowed)
				(vias not_allowed)
				(pads allowed)
				(copperpour not_allowed)
				(footprints allowed)
			)
			(placement
				(enabled no)
				(sheetname "")
			)
			(fill
				(thermal_gap 0.5)
				(thermal_bridge_width 0.5)
				(island_removal_mode 0)
			)
			(polygon
				(pts
					(xy 387.711188 -58.07075) (xy 387.711188 -57.56275) (xy 388.092188 -57.56275) (xy 388.092188 -58.07075)
				)
			)
		)
		(zone
			(layer "B.Cu")
			(hatch none 0.5)
			(connect_pads
				(clearance 0)
			)
			(min_thickness 0.25)
			(keepout
				(tracks not_allowed)
				(vias allowed)
				(pads allowed)
				(copperpour not_allowed)
				(footprints allowed)
			)
			(placement
				(enabled no)
				(sheetname "")
			)
			(fill
				(thermal_gap 0.5)
				(thermal_bridge_width 0.5)
				(island_removal_mode 0)
			)
			(polygon
				(pts
					(xy 388.092188 -58.07075) (xy 388.092188 -57.56275) (xy 387.711188 -57.56275) (xy 387.711188 -58.07075)
				)
			)
		)
	)
	(footprint ""
		(layer "B.Cu")
		(at 63.2968 -89.9922 90)
		(property "Reference" "R8N4"
			(at 0 0 90)
			(layer "B.SilkS")
			(hide yes)
			(effects
				(font
					(size 1.27 1.27)
				)
				(justify mirror)
			)
		)
		(property "Value" ""
			(at 0 0 90)
			(layer "B.Fab")
			(effects
				(font
					(size 1.27 1.27)
				)
				(justify mirror)
			)
		)
		(duplicate_pad_numbers_are_jumpers no)
		(fp_poly
			(pts
				(xy 0.2794 -0.1016) (xy -0.2794 -0.1016) (xy -0.2794 0.9906) (xy 0.2794 0.9906)
			)
			(stroke
				(width 0)
				(type default)
			)
			(fill no)
			(layer "B.CrtYd")
		)
		(fp_line
			(start 0.2794 -0.1016)
			(end 0.2794 0.9906)
			(stroke
				(width 0.1)
				(type default)
			)
			(layer "B.Fab")
		)
		(fp_line
			(start -0.2794 -0.1016)
			(end 0.2794 -0.1016)
			(stroke
				(width 0.1)
				(type default)
			)
			(layer "B.Fab")
		)
		(fp_line
			(start 0.2794 0.9906)
			(end -0.2794 0.9906)
			(stroke
				(width 0.1)
				(type default)
			)
			(layer "B.Fab")
		)
		(fp_line
			(start -0.2794 0.9906)
			(end -0.2794 -0.1016)
			(stroke
				(width 0.1)
				(type default)
			)
			(layer "B.Fab")
		)
		(pad "1" smd rect
			(at 0 0 270)
			(size 0.508 0.508)
			(layers "B.Cu" "B.Mask" "B.Paste")
			(net "P3V3_STBY")
		)
		(pad "2" smd rect
			(at 0 0.889 270)
			(size 0.508 0.508)
			(layers "B.Cu" "B.Mask" "B.Paste")
			(net "FM_CPU1_PROC_ID0")
		)
		(zone
			(layer "B.Cu")
			(hatch none 0.5)
			(connect_pads
				(clearance 0)
			)
			(min_thickness 0.25)
			(keepout
				(tracks allowed)
				(vias not_allowed)
				(pads allowed)
				(copperpour not_allowed)
				(footprints allowed)
			)
			(placement
				(enabled no)
				(sheetname "")
			)
			(fill
				(thermal_gap 0.5)
				(thermal_bridge_width 0.5)
				(island_removal_mode 0)
			)
			(polygon
				(pts
					(xy 63.5508 -90.2462) (xy 63.5508 -89.7382) (xy 63.9318 -89.7382) (xy 63.9318 -90.2462)
				)
			)
		)
		(zone
			(layer "B.Cu")
			(hatch none 0.5)
			(connect_pads
				(clearance 0)
			)
			(min_thickness 0.25)
			(keepout
				(tracks not_allowed)
				(vias allowed)
				(pads allowed)
				(copperpour not_allowed)
				(footprints allowed)
			)
			(placement
				(enabled no)
				(sheetname "")
			)
			(fill
				(thermal_gap 0.5)
				(thermal_bridge_width 0.5)
				(island_removal_mode 0)
			)
			(polygon
				(pts
					(xy 63.9318 -90.2462) (xy 63.9318 -89.7382) (xy 63.5508 -89.7382) (xy 63.5508 -90.2462)
				)
			)
		)
	)
	(footprint ""
		(layer "B.Cu")
		(at 427.736 -142.0876)
		(property "Reference" "C2L39"
			(at 0 0 0)
			(layer "B.SilkS")
			(hide yes)
			(effects
				(font
					(size 1.27 1.27)
				)
				(justify mirror)
			)
		)
		(property "Value" ""
			(at 0 0 0)
			(layer "B.Fab")
			(effects
				(font
					(size 1.27 1.27)
				)
				(justify mirror)
			)
		)
		(duplicate_pad_numbers_are_jumpers no)
		(fp_poly
			(pts
				(xy -0.3048 -0.1016) (xy -0.3048 0.9906) (xy 0.3048 0.9906) (xy 0.3048 -0.1016)
			)
			(stroke
				(width 0)
				(type default)
			)
			(fill no)
			(layer "B.CrtYd")
		)
		(fp_line
			(start -0.3048 -0.1016)
			(end 0.3048 -0.1016)
			(stroke
				(width 0.1)
				(type default)
			)
			(layer "B.Fab")
		)
		(fp_line
			(start -0.3048 0.9906)
			(end -0.3048 -0.1016)
			(stroke
				(width 0.1)
				(type default)
			)
			(layer "B.Fab")
		)
		(fp_line
			(start 0.3048 -0.1016)
			(end 0.3048 0.9906)
			(stroke
				(width 0.1)
				(type default)
			)
			(layer "B.Fab")
		)
		(fp_line
			(start 0.3048 0.9906)
			(end -0.3048 0.9906)
			(stroke
				(width 0.1)
				(type default)
			)
			(layer "B.Fab")
		)
		(pad "1" smd rect
			(at 0 0 180)
			(size 0.508 0.508)
			(layers "B.Cu" "B.Mask" "B.Paste")
			(net "SATA6G_P0_TX_C_DP")
		)
		(pad "2" smd rect
			(at 0 0.889 180)
			(size 0.508 0.508)
			(layers "B.Cu" "B.Mask" "B.Paste")
			(net "SATA6G_PCH_PCIE_UP_SATA_TXP<0>")
		)
		(zone
			(layer "B.Cu")
			(hatch none 0.5)
			(connect_pads
				(clearance 0)
			)
			(min_thickness 0.25)
			(keepout
				(tracks allowed)
				(vias not_allowed)
				(pads allowed)
				(copperpour not_allowed)
				(footprints allowed)
			)
			(placement
				(enabled no)
				(sheetname "")
			)
			(fill
				(thermal_gap 0.5)
				(thermal_bridge_width 0.5)
				(island_removal_mode 0)
			)
			(polygon
				(pts
					(xy 427.99 -141.8336) (xy 427.482 -141.8336) (xy 427.482 -141.4526) (xy 427.99 -141.4526)
				)
			)
		)
		(zone
			(layer "B.Cu")
			(hatch none 0.5)
			(connect_pads
				(clearance 0)
			)
			(min_thickness 0.25)
			(keepout
				(tracks not_allowed)
				(vias allowed)
				(pads allowed)
				(copperpour not_allowed)
				(footprints allowed)
			)
			(placement
				(enabled no)
				(sheetname "")
			)
			(fill
				(thermal_gap 0.5)
				(thermal_bridge_width 0.5)
				(island_removal_mode 0)
			)
			(polygon
				(pts
					(xy 427.99 -141.4526) (xy 427.482 -141.4526) (xy 427.482 -141.8336) (xy 427.99 -141.8336)
				)
			)
		)
	)
)
